(kicad_pcb
	(version 20241229)
	(generator "pcbnew")
	(generator_version "9.0")
	(general
		(thickness 1.6296)
		(legacy_teardrops no)
	)
	(paper "A3")
	(title_block
		(title "Thunderbolt to 10GbE adapter")
		(date "2026-04-21")
		(rev "1.1.0")
		(company "Antmicro Ltd")
		(comment 1 "www.antmicro.com")
		(comment 9 "footprint 4 of 703 (U4), pads 246-327 of 337")
	)
	(layers
		(0 "F.Cu" signal)
		(4 "In1.Cu" signal)
		(6 "In2.Cu" signal)
		(8 "In3.Cu" signal)
		(10 "In4.Cu" signal)
		(12 "In5.Cu" signal)
		(14 "In6.Cu" signal)
		(2 "B.Cu" signal)
		(9 "F.Adhes" user "F.Adhesive")
		(11 "B.Adhes" user "B.Adhesive")
		(13 "F.Paste" user)
		(15 "B.Paste" user)
		(5 "F.SilkS" user "F.Silkscreen")
		(7 "B.SilkS" user "B.Silkscreen")
		(1 "F.Mask" user)
		(3 "B.Mask" user)
		(17 "Dwgs.User" user "User.Drawings")
		(19 "Cmts.User" user "User.Comments")
		(21 "Eco1.User" user "User.Eco1")
		(23 "Eco2.User" user "User.Eco2")
		(25 "Edge.Cuts" user)
		(27 "Margin" user)
		(31 "F.CrtYd" user "F.Courtyard")
		(29 "B.CrtYd" user "B.Courtyard")
		(35 "F.Fab" user)
		(33 "B.Fab" user)
	)
	(footprint "antmicro-footprints:JHL6340SLLSQ"
		(layer "F.Cu")
		(at 128.5 123.95 180)
		(property "Reference" "U4"
			(at 4.9 6.15 0)
			(unlocked yes)
			(layer "F.SilkS")
			(effects
				(font
					(size 0.7 0.7)
					(thickness 0.15)
				)
			)
		)
		(property "Value" "JHL6340SLLSQ"
			(at 0 6.4 180)
			(unlocked yes)
			(layer "F.Fab")
			(effects
				(font
					(size 0.7 0.7)
					(thickness 0.15)
				)
			)
		)
		(property "Datasheet" "https://www.thunderbolttechnology.net/sites/default/files/18-241_ThunderboltController_Brief_HI.pdf"
			(at 0 0 180)
			(layer "F.Fab")
			(hide yes)
			(effects
				(font
					(size 1.27 1.27)
					(thickness 0.15)
				)
			)
		)
		(property "Description" "Thunderbolt™ 3 Controller, I/O"
			(at 0 0 180)
			(layer "F.Fab")
			(hide yes)
			(effects
				(font
					(size 1.27 1.27)
					(thickness 0.15)
				)
			)
		)
		(property "Manufacturer" "Intel"
			(at 0 0 180)
			(unlocked yes)
			(layer "F.Fab")
			(hide yes)
			(effects
				(font
					(size 1 1)
					(thickness 0.15)
				)
			)
		)
		(property "MPN" "JHL6340SLLSQ"
			(at 0 0 180)
			(unlocked yes)
			(layer "F.Fab")
			(hide yes)
			(effects
				(font
					(size 1 1)
					(thickness 0.15)
				)
			)
		)
		(property "Author" "Antmicro"
			(at 0 0 180)
			(unlocked yes)
			(layer "F.Fab")
			(hide yes)
			(effects
				(font
					(size 1 1)
					(thickness 0.15)
				)
			)
		)
		(property "License" "Apache-2.0"
			(at 0 0 180)
			(unlocked yes)
			(layer "F.Fab")
			(hide yes)
			(effects
				(font
					(size 1 1)
					(thickness 0.15)
				)
			)
		)
		(sheetname "/TB Controller/")
		(sheetfile "tb.kicad_sch")
		(attr smd)
		(pad "P2" smd circle
			(at -4.6 0.92 180)
			(size 0.254 0.254)
			(layers "F.Cu" "F.Mask" "F.Paste")
			(net 23 "GND")
			(pinfunction "VSS_ANA")
			(pintype "passive")
		)
		(pad "P22" smd circle
			(at 4.6 0.92 180)
			(size 0.254 0.254)
			(layers "F.Cu" "F.Mask" "F.Paste")
			(net 316 "/TB Controller/TB_PCIE_TX1_N")
			(pinfunction "PCIE_TX1_N")
			(pintype "input")
		)
		(pad "P23" smd oval
			(at 5.06 0.92 270)
			(size 0.1578 0.3302)
			(layers "F.Cu" "F.Mask" "F.Paste")
			(net 325 "/TB Controller/TB_PCIE_TX1_P")
			(pinfunction "PCIE_TX1_P")
			(pintype "input")
		)
		(pad "R1" smd oval
			(at -5.06 1.38 270)
			(size 0.1578 0.3302)
			(layers "F.Cu" "F.Mask" "F.Paste")
			(net 279 "unconnected-(U4C-DPSRC_ML0_N-PadR1)")
			(pinfunction "DPSRC_ML0_N")
			(pintype "output+no_connect")
		)
		(pad "R2" smd circle
			(at -4.6 1.38 180)
			(size 0.254 0.254)
			(layers "F.Cu" "F.Mask" "F.Paste")
			(net 280 "unconnected-(U4C-DPSRC_ML0_P-PadR2)")
			(pinfunction "DPSRC_ML0_P")
			(pintype "output+no_connect")
		)
		(pad "R4" smd circle
			(at -3.9 1.3 180)
			(size 0.254 0.254)
			(layers "F.Cu" "F.Mask" "F.Paste")
			(net 219 "Net-(U4C-DPSNK0_DDC_DATA)")
			(pinfunction "DPSNK0_DDC_DATA")
			(pintype "passive")
		)
		(pad "R5" smd circle
			(at -3.25 1.3 180)
			(size 0.254 0.254)
			(layers "F.Cu" "F.Mask" "F.Paste")
			(net 23 "GND")
			(pinfunction "VSS_ANA")
			(pintype "passive")
		)
		(pad "R6" smd circle
			(at -2.6 1.3 180)
			(size 0.254 0.254)
			(layers "F.Cu" "F.Mask" "F.Paste")
			(net 179 "Net-(U4A-VCC3P3_LC)")
			(pinfunction "VCC3P3_LC")
			(pintype "power_in")
		)
		(pad "R8" smd circle
			(at -1.95 1.3 180)
			(size 0.254 0.254)
			(layers "F.Cu" "F.Mask" "F.Paste")
			(net 404 "Net-(C58-Pad2)")
			(pinfunction "VCC0P9_CIO")
			(pintype "passive")
		)
		(pad "R9" smd circle
			(at -1.3 1.3 180)
			(size 0.254 0.254)
			(layers "F.Cu" "F.Mask" "F.Paste")
			(net 404 "Net-(C58-Pad2)")
			(pinfunction "VCC0P9_CIO")
			(pintype "passive")
		)
		(pad "R11" smd circle
			(at -0.65 1.3 180)
			(size 0.254 0.254)
			(layers "F.Cu" "F.Mask" "F.Paste")
			(net 404 "Net-(C58-Pad2)")
			(pinfunction "VCC0P9_CIO")
			(pintype "power_in")
		)
		(pad "R12" smd circle
			(at 0 1.3 180)
			(size 0.254 0.254)
			(layers "F.Cu" "F.Mask" "F.Paste")
			(net 404 "Net-(C58-Pad2)")
			(pinfunction "VCC0P9_CIO")
			(pintype "passive")
		)
		(pad "R13" smd circle
			(at 0.65 1.3 180)
			(size 0.254 0.254)
			(layers "F.Cu" "F.Mask" "F.Paste")
			(net 181 "Net-(U4A-VCC3P3_S0)")
			(pinfunction "VCC3P3_S0")
			(pintype "power_in")
		)
		(pad "R15" smd circle
			(at 1.3 1.3 180)
			(size 0.254 0.254)
			(layers "F.Cu" "F.Mask" "F.Paste")
			(net 405 "Net-(C66-Pad2)")
			(pinfunction "VCC0P9_USB")
			(pintype "power_in")
		)
		(pad "R16" smd circle
			(at 1.95 1.3 180)
			(size 0.254 0.254)
			(layers "F.Cu" "F.Mask" "F.Paste")
			(net 405 "Net-(C66-Pad2)")
			(pinfunction "VCC0P9_USB")
			(pintype "passive")
		)
		(pad "R18" smd circle
			(at 2.6 1.3 180)
			(size 0.254 0.254)
			(layers "F.Cu" "F.Mask" "F.Paste")
			(net 23 "GND")
			(pinfunction "VSS_ANA")
			(pintype "passive")
		)
		(pad "R19" smd circle
			(at 3.25 1.3 180)
			(size 0.254 0.254)
			(layers "F.Cu" "F.Mask" "F.Paste")
			(net 23 "GND")
			(pinfunction "VSS_ANA")
			(pintype "passive")
		)
		(pad "R20" smd circle
			(at 3.9 1.3 180)
			(size 0.254 0.254)
			(layers "F.Cu" "F.Mask" "F.Paste")
			(net 23 "GND")
			(pinfunction "VSS_ANA")
			(pintype "passive")
		)
		(pad "R22" smd circle
			(at 4.6 1.38 180)
			(size 0.254 0.254)
			(layers "F.Cu" "F.Mask" "F.Paste")
			(net 23 "GND")
			(pinfunction "VSS_ANA")
			(pintype "passive")
		)
		(pad "R23" smd oval
			(at 5.06 1.38 270)
			(size 0.1578 0.3302)
			(layers "F.Cu" "F.Mask" "F.Paste")
			(net 23 "GND")
			(pinfunction "VSS_ANA")
			(pintype "passive")
		)
		(pad "T1" smd oval
			(at -5.06 1.84 270)
			(size 0.1578 0.3302)
			(layers "F.Cu" "F.Mask" "F.Paste")
			(net 23 "GND")
			(pinfunction "VSS_ANA")
			(pintype "passive")
		)
		(pad "T2" smd circle
			(at -4.6 1.84 180)
			(size 0.254 0.254)
			(layers "F.Cu" "F.Mask" "F.Paste")
			(net 23 "GND")
			(pinfunction "VSS_ANA")
			(pintype "passive")
		)
		(pad "T4" smd circle
			(at -3.9 1.95 180)
			(size 0.254 0.254)
			(layers "F.Cu" "F.Mask" "F.Paste")
			(net 226 "Net-(U4D-TCK)")
			(pinfunction "TCK")
			(pintype "input")
		)
		(pad "T5" smd circle
			(at -3.25 1.95 180)
			(size 0.254 0.254)
			(layers "F.Cu" "F.Mask" "F.Paste")
			(net 23 "GND")
			(pinfunction "VSS_ANA")
			(pintype "passive")
		)
		(pad "T6" smd circle
			(at -2.6 1.95 180)
			(size 0.254 0.254)
			(layers "F.Cu" "F.Mask" "F.Paste")
			(net 23 "GND")
			(pinfunction "VSS")
			(pintype "passive")
		)
		(pad "T8" smd circle
			(at -1.95 1.95 180)
			(size 0.254 0.254)
			(layers "F.Cu" "F.Mask" "F.Paste")
			(net 23 "GND")
			(pinfunction "VSS")
			(pintype "passive")
		)
		(pad "T9" smd circle
			(at -1.3 1.95 180)
			(size 0.254 0.254)
			(layers "F.Cu" "F.Mask" "F.Paste")
			(net 23 "GND")
			(pinfunction "VSS")
			(pintype "passive")
		)
		(pad "T11" smd circle
			(at -0.65 1.95 180)
			(size 0.254 0.254)
			(layers "F.Cu" "F.Mask" "F.Paste")
			(net 402 "Net-(C52-Pad2)")
			(pinfunction "VCC0P9_DP")
			(pintype "passive")
		)
		(pad "T12" smd circle
			(at 0 1.95 180)
			(size 0.254 0.254)
			(layers "F.Cu" "F.Mask" "F.Paste")
			(net 402 "Net-(C52-Pad2)")
			(pinfunction "VCC0P9_DP")
			(pintype "passive")
		)
		(pad "T13" smd circle
			(at 0.65 1.95 180)
			(size 0.254 0.254)
			(layers "F.Cu" "F.Mask" "F.Paste")
			(net 23 "GND")
			(pinfunction "VSS")
			(pintype "passive")
		)
		(pad "T15" smd circle
			(at 1.3 1.95 180)
			(size 0.254 0.254)
			(layers "F.Cu" "F.Mask" "F.Paste")
			(net 23 "GND")
			(pinfunction "VSS")
			(pintype "passive")
		)
		(pad "T16" smd circle
			(at 1.95 1.95 180)
			(size 0.254 0.254)
			(layers "F.Cu" "F.Mask" "F.Paste")
			(net 23 "GND")
			(pinfunction "VSS")
			(pintype "passive")
		)
		(pad "T18" smd circle
			(at 2.6 1.95 180)
			(size 0.254 0.254)
			(layers "F.Cu" "F.Mask" "F.Paste")
			(net 23 "GND")
			(pinfunction "VSS")
			(pintype "passive")
		)
		(pad "T19" smd circle
			(at 3.25 1.95 180)
			(size 0.254 0.254)
			(layers "F.Cu" "F.Mask" "F.Paste")
			(net 214 "/TB Controller/PCIE_CLK_JHL_N")
			(pinfunction "PCIE_REFCLK_100_IN_N")
			(pintype "input")
		)
		(pad "T20" smd circle
			(at 3.9 1.95 180)
			(size 0.254 0.254)
			(layers "F.Cu" "F.Mask" "F.Paste")
			(net 23 "GND")
			(pinfunction "VSS_ANA")
			(pintype "passive")
		)
		(pad "T22" smd circle
			(at 4.6 1.84 180)
			(size 0.254 0.254)
			(layers "F.Cu" "F.Mask" "F.Paste")
			(net 599 "/TB Controller/PCIex4.TX1-")
			(pinfunction "PCIE_RX1_N")
			(pintype "input")
		)
		(pad "T23" smd oval
			(at 5.06 1.84 270)
			(size 0.1578 0.3302)
			(layers "F.Cu" "F.Mask" "F.Paste")
			(net 600 "/TB Controller/PCIex4.TX1+")
			(pinfunction "PCIE_RX1_P")
			(pintype "input")
		)
		(pad "U1" smd oval
			(at -5.06 2.3 270)
			(size 0.1578 0.3302)
			(layers "F.Cu" "F.Mask" "F.Paste")
			(net 375 "/PD and TB DC-DC/I2C1.SDA")
			(pinfunction "GPIO_0")
			(pintype "bidirectional")
		)
		(pad "U2" smd circle
			(at -4.6 2.3 180)
			(size 0.254 0.254)
			(layers "F.Cu" "F.Mask" "F.Paste")
			(net 373 "/PD and TB DC-DC/I2C1.SCL")
			(pinfunction "GPIO_1")
			(pintype "bidirectional")
		)
		(pad "U22" smd circle
			(at 4.6 2.3 180)
			(size 0.254 0.254)
			(layers "F.Cu" "F.Mask" "F.Paste")
			(net 23 "GND")
			(pinfunction "VSS_ANA")
			(pintype "passive")
		)
		(pad "U23" smd oval
			(at 5.06 2.3 270)
			(size 0.1578 0.3302)
			(layers "F.Cu" "F.Mask" "F.Paste")
			(net 23 "GND")
			(pinfunction "VSS_ANA")
			(pintype "passive")
		)
		(pad "V1" smd oval
			(at -5.06 2.76 270)
			(size 0.1578 0.3302)
			(layers "F.Cu" "F.Mask" "F.Paste")
			(net 358 "/TB flash memory/FLASH_WP")
			(pinfunction "GPIO_2")
			(pintype "bidirectional")
		)
		(pad "V2" smd circle
			(at -4.6 2.76 180)
			(size 0.254 0.254)
			(layers "F.Cu" "F.Mask" "F.Paste")
			(net 186 "Net-(U4C-GPIO_3)")
			(pinfunction "GPIO_3")
			(pintype "bidirectional")
		)
		(pad "V4" smd circle
			(at -3.9 2.6 180)
			(size 0.254 0.254)
			(layers "F.Cu" "F.Mask" "F.Paste")
			(net 225 "Net-(U4D-TMS)")
			(pinfunction "TMS")
			(pintype "input")
		)
		(pad "V5" smd circle
			(at -3.25 2.6 180)
			(size 0.254 0.254)
			(layers "F.Cu" "F.Mask" "F.Paste")
			(net 23 "GND")
			(pinfunction "VSS_ANA")
			(pintype "passive")
		)
		(pad "V6" smd circle
			(at -2.6 2.6 180)
			(size 0.254 0.254)
			(layers "F.Cu" "F.Mask" "F.Paste")
			(net 23 "GND")
			(pinfunction "VSS_ANA")
			(pintype "passive")
		)
		(pad "V8" smd circle
			(at -1.95 2.6 180)
			(size 0.254 0.254)
			(layers "F.Cu" "F.Mask" "F.Paste")
			(net 23 "GND")
			(pinfunction "VSS_ANA")
			(pintype "passive")
		)
		(pad "V9" smd circle
			(at -1.3 2.6 180)
			(size 0.254 0.254)
			(layers "F.Cu" "F.Mask" "F.Paste")
			(net 23 "GND")
			(pinfunction "VSS_ANA")
			(pintype "passive")
		)
		(pad "V11" smd circle
			(at -0.65 2.6 180)
			(size 0.254 0.254)
			(layers "F.Cu" "F.Mask" "F.Paste")
			(net 402 "Net-(C52-Pad2)")
			(pinfunction "VCC0P9_ANA_DPSNK")
			(pintype "power_in")
		)
		(pad "V12" smd circle
			(at 0 2.6 180)
			(size 0.254 0.254)
			(layers "F.Cu" "F.Mask" "F.Paste")
			(net 402 "Net-(C52-Pad2)")
			(pinfunction "VCC0P9_ANA_DPSNK")
			(pintype "passive")
		)
		(pad "V13" smd circle
			(at 0.65 2.6 180)
			(size 0.254 0.254)
			(layers "F.Cu" "F.Mask" "F.Paste")
			(net 402 "Net-(C52-Pad2)")
			(pinfunction "VCC0P9_ANA_DPSNK")
			(pintype "passive")
		)
		(pad "V15" smd circle
			(at 1.3 2.6 180)
			(size 0.254 0.254)
			(layers "F.Cu" "F.Mask" "F.Paste")
			(net 23 "GND")
			(pinfunction "VSS_ANA")
			(pintype "passive")
		)
		(pad "V16" smd circle
			(at 1.95 2.6 180)
			(size 0.254 0.254)
			(layers "F.Cu" "F.Mask" "F.Paste")
			(net 23 "GND")
			(pinfunction "VSS_ANA")
			(pintype "passive")
		)
		(pad "V18" smd circle
			(at 2.6 2.6 180)
			(size 0.254 0.254)
			(layers "F.Cu" "F.Mask" "F.Paste")
			(net 281 "unconnected-(U4F-PCIE_ATEST-PadV18)")
			(pinfunction "PCIE_ATEST")
			(pintype "passive+no_connect")
		)
		(pad "V19" smd circle
			(at 3.25 2.6 180)
			(size 0.254 0.254)
			(layers "F.Cu" "F.Mask" "F.Paste")
			(net 213 "/TB Controller/PCIE_CLK_JHL_P")
			(pinfunction "PCIE_REFCLK_100_IN_P")
			(pintype "input")
		)
		(pad "V20" smd circle
			(at 3.9 2.6 180)
			(size 0.254 0.254)
			(layers "F.Cu" "F.Mask" "F.Paste")
			(net 23 "GND")
			(pinfunction "VSS_ANA")
			(pintype "passive")
		)
		(pad "V22" smd circle
			(at 4.6 2.76 180)
			(size 0.254 0.254)
			(layers "F.Cu" "F.Mask" "F.Paste")
			(net 315 "/TB Controller/TB_PCIE_TX0_N")
			(pinfunction "PCIE_TX0_N")
			(pintype "input")
		)
		(pad "V23" smd oval
			(at 5.06 2.76 270)
			(size 0.1578 0.3302)
			(layers "F.Cu" "F.Mask" "F.Paste")
			(net 323 "/TB Controller/TB_PCIE_TX0_P")
			(pinfunction "PCIE_TX0_P")
			(pintype "input")
		)
		(pad "W1" smd oval
			(at -5.06 3.22 270)
			(size 0.1578 0.3302)
			(layers "F.Cu" "F.Mask" "F.Paste")
			(net 187 "Net-(U4C-GPIO_4)")
			(pinfunction "GPIO_4")
			(pintype "bidirectional")
		)
		(pad "W2" smd circle
			(at -4.6 3.22 180)
			(size 0.254 0.254)
			(layers "F.Cu" "F.Mask" "F.Paste")
			(net 188 "Net-(U4C-GPIO_5)")
			(pinfunction "GPIO_5")
			(pintype "bidirectional")
		)
		(pad "W4" smd circle
			(at -3.9 3.25 180)
			(size 0.254 0.254)
			(layers "F.Cu" "F.Mask" "F.Paste")
			(net 227 "Net-(U4D-TDO)")
			(pinfunction "TDO")
			(pintype "output")
		)
		(pad "W5" smd circle
			(at -3.25 3.25 180)
			(size 0.254 0.254)
			(layers "F.Cu" "F.Mask" "F.Paste")
			(net 23 "GND")
			(pinfunction "VSS_ANA")
			(pintype "passive")
		)
		(pad "W6" smd circle
			(at -2.6 3.25 180)
			(size 0.254 0.254)
			(layers "F.Cu" "F.Mask" "F.Paste")
			(net 23 "GND")
			(pinfunction "VSS_ANA")
			(pintype "passive")
		)
		(pad "W8" smd circle
			(at -1.95 3.25 180)
			(size 0.254 0.254)
			(layers "F.Cu" "F.Mask" "F.Paste")
			(net 23 "GND")
			(pinfunction "VSS_ANA")
			(pintype "passive")
		)
		(pad "W9" smd circle
			(at -1.3 3.25 180)
			(size 0.254 0.254)
			(layers "F.Cu" "F.Mask" "F.Paste")
			(net 23 "GND")
			(pinfunction "VSS_ANA")
			(pintype "passive")
		)
		(pad "W11" smd circle
			(at -0.65 3.25 180)
			(size 0.254 0.254)
			(layers "F.Cu" "F.Mask" "F.Paste")
			(net 282 "unconnected-(U4C-DPSNK0_AUX_N-PadW11)")
			(pinfunction "DPSNK0_AUX_N")
			(pintype "bidirectional+no_connect")
		)
		(pad "W12" smd circle
			(at 0 3.25 180)
			(size 0.254 0.254)
			(layers "F.Cu" "F.Mask" "F.Paste")
			(net 283 "unconnected-(U4C-DPSNK1_AUX_N-PadW12)")
			(pinfunction "DPSNK1_AUX_N")
			(pintype "bidirectional+no_connect")
		)
		(pad "W13" smd circle
			(at 0.65 3.25 180)
			(size 0.254 0.254)
			(layers "F.Cu" "F.Mask" "F.Paste")
			(net 23 "GND")
			(pinfunction "MONDC_DPSNK_0")
			(pintype "passive")
		)
		(pad "W15" smd circle
			(at 1.3 3.25 180)
			(size 0.254 0.254)
			(layers "F.Cu" "F.Mask" "F.Paste")
			(net 240 "/TB Controller/PA_AUX_N")
			(pinfunction "PA_DPSRC_AUX_N")
			(pintype "bidirectional")
		)
		(pad "W16" smd circle
			(at 1.95 3.25 180)
			(size 0.254 0.254)
			(layers "F.Cu" "F.Mask" "F.Paste")
			(net 284 "unconnected-(U4E-PB_DPSRC_AUX_N-PadW16)")
			(pinfunction "PB_DPSRC_AUX_N")
			(pintype "bidirectional+no_connect")
		)
		(pad "W18" smd circle
			(at 2.6 3.25 180)
			(size 0.254 0.254)
			(layers "F.Cu" "F.Mask" "F.Paste")
			(net 23 "GND")
			(pinfunction "MONDC_DPSNK_1")
			(pintype "passive")
		)
		(pad "W19" smd circle
			(at 3.25 3.25 180)
			(size 0.254 0.254)
			(layers "F.Cu" "F.Mask" "F.Paste")
			(net 285 "unconnected-(U4C-DPSRC_AUX_P-PadW19)")
			(pinfunction "DPSRC_AUX_P")
			(pintype "bidirectional+no_connect")
		)
		(pad "W20" smd circle
			(at 3.9 3.25 180)
			(size 0.254 0.254)
			(layers "F.Cu" "F.Mask" "F.Paste")
			(net 23 "GND")
			(pinfunction "VSS_ANA")
			(pintype "passive")
		)
		(pad "W22" smd circle
			(at 4.6 3.22 180)
			(size 0.254 0.254)
			(layers "F.Cu" "F.Mask" "F.Paste")
			(net 23 "GND")
			(pinfunction "VSS_ANA")
			(pintype "passive")
		)
		(pad "W23" smd oval
			(at 5.06 3.22 270)
			(size 0.1578 0.3302)
			(layers "F.Cu" "F.Mask" "F.Paste")
			(net 23 "GND")
			(pinfunction "VSS_ANA")
			(pintype "passive")
		)
		(pad "Y1" smd oval
			(at -5.06 3.68 270)
			(size 0.1578 0.3302)
			(layers "F.Cu" "F.Mask" "F.Paste")
			(net 189 "Net-(U4C-GPIO_6)")
			(pinfunction "GPIO_6")
			(pintype "bidirectional")
		)
		(pad "Y2" smd circle
			(at -4.6 3.68 180)
			(size 0.254 0.254)
			(layers "F.Cu" "F.Mask" "F.Paste")
			(net 190 "Net-(U4C-GPIO_7)")
			(pinfunction "GPIO_7")
			(pintype "bidirectional")
		)
		(pad "Y4" smd circle
			(at -3.9 3.9 180)
			(size 0.254 0.254)
			(layers "F.Cu" "F.Mask" "F.Paste")
			(net 224 "Net-(U4D-TDI)")
			(pinfunction "TDI")
			(pintype "input")
		)
		(pad "Y5" smd circle
			(at -3.25 3.9 180)
			(size 0.254 0.254)
			(layers "F.Cu" "F.Mask" "F.Paste")
			(net 218 "Net-(U4C-DPSNK0_DDC_CLK)")
			(pinfunction "DPSNK0_DDC_CLK")
			(pintype "passive")
		)
		(pad "Y6" smd circle
			(at -2.6 3.9 180)
			(size 0.254 0.254)
			(layers "F.Cu" "F.Mask" "F.Paste")
			(net 220 "Net-(U4C-DPSNK1_HPD)")
			(pinfunction "DPSNK1_HPD")
			(pintype "passive")
		)
		(pad "Y8" smd circle
			(at -1.95 3.9 180)
			(size 0.254 0.254)
			(layers "F.Cu" "F.Mask" "F.Paste")
			(net 221 "Net-(U4C-DPSNK1_DDC_CLK)")
			(pinfunction "DPSNK1_DDC_CLK")
			(pintype "passive")
		)
		(pad "Y9" smd circle
			(at -1.3 3.9 180)
			(size 0.254 0.254)
			(layers "F.Cu" "F.Mask" "F.Paste")
			(net 23 "GND")
			(pinfunction "VSS_ANA")
			(pintype "passive")
		)
	)
)
